(kicad_pcb
	(version 20260206)
	(generator "pcbnew")
	(generator_version "10.0")
	(general
		(thickness 1.6)
		(legacy_teardrops no)
	)
	(paper "A4")
	(title_block
		(title "fcb — Lightning_FCB_BRD.brd")
		(comment 1 "Lightning (Wiwynn / Facebook NVMe JBOF) / footprints 305-309 of 495")
	)
	(layers
		(0 "F.Cu" signal "TOP")
		(4 "In1.Cu" signal "L2GND")
		(6 "In2.Cu" signal "L3VCC")
		(2 "B.Cu" signal "BOTTOM")
		(9 "F.Adhes" user "F.Adhesive")
		(11 "B.Adhes" user "B.Adhesive")
		(13 "F.Paste" user "Package Geometry/Pastemask Top")
		(15 "B.Paste" user "Package Geometry/Pastemask Bottom")
		(5 "F.SilkS" user "Ref Des/Silkscreen Top")
		(7 "B.SilkS" user "Ref Des/Silkscreen Bottom")
		(1 "F.Mask" user "Board Geometry/Soldermask Top")
		(3 "B.Mask" user "Board Geometry/Soldermask Bottom")
		(17 "Dwgs.User" user "User.Drawings")
		(19 "Cmts.User" user "User.Comments")
		(21 "Eco1.User" user "User.Eco1")
		(23 "Eco2.User" user "User.Eco2")
		(25 "Edge.Cuts" user "Board Geometry/Outline")
		(27 "Margin" user)
		(31 "F.CrtYd" user "Package Geometry/Place Bound Top")
		(29 "B.CrtYd" user "Package Geometry/Place Bound Bottom")
		(35 "F.Fab" user "Ref Des/Assembly Top")
		(33 "B.Fab" user "Ref Des/Assembly Bottom")
	)
	(footprint ""
		(layer "F.Cu")
		(at 40.2844 -366.319816)
		(property "Reference" "D18"
			(at 0 0 0)
			(layer "F.SilkS")
			(hide yes)
			(effects
				(font
					(size 1.27 1.27)
				)
			)
		)
		(property "Value" "CH751H-40PT-1GP"
			(at -0.1016 -4.4958 0)
			(unlocked yes)
			(layer "F.Fab")
			(hide yes)
			(effects
				(font
					(size 1.016 1.016)
					(thickness 0.1524)
				)
			)
		)
		(property "Device Type" "SOD80CAKH36"
			(at -0.1016 -6.0198 0)
			(unlocked yes)
			(layer "F.Fab")
			(hide yes)
			(effects
				(font
					(size 1.016 1.016)
					(thickness 0.1524)
				)
			)
		)
		(duplicate_pad_numbers_are_jumpers no)
		(fp_line
			(start -0.8128 -1.8796)
			(end -0.8128 1.8796)
			(stroke
				(width 0.1524)
				(type default)
			)
			(layer "F.SilkS")
		)
		(fp_line
			(start -0.8128 1.8796)
			(end 0.8128 1.8796)
			(stroke
				(width 0.1524)
				(type default)
			)
			(layer "F.SilkS")
		)
		(fp_line
			(start -0.6858 2.0066)
			(end 0.6858 2.0066)
			(stroke
				(width 0.4064)
				(type default)
			)
			(layer "F.SilkS")
		)
		(fp_line
			(start 0.8128 -1.8796)
			(end -0.8128 -1.8796)
			(stroke
				(width 0.1524)
				(type default)
			)
			(layer "F.SilkS")
		)
		(fp_line
			(start 0.8128 1.8796)
			(end 0.8128 -1.8796)
			(stroke
				(width 0.1524)
				(type default)
			)
			(layer "F.SilkS")
		)
		(fp_rect
			(start -0.889 2.2098)
			(end 0.889 -1.9558)
			(stroke
				(width 0)
				(type default)
			)
			(fill no)
			(layer "F.CrtYd")
		)
		(fp_rect
			(start -0.889 2.2098)
			(end 0.889 -1.9558)
			(stroke
				(width 0)
				(type default)
			)
			(fill no)
			(layer "F.Fab")
		)
		(pad "A" smd rect
			(at 0 -1.0668)
			(size 0.762 1.1684)
			(layers "F.Cu" "F.Mask" "F.Paste")
			(net "TEMP_ALM#_REVERSE")
		)
		(pad "K" smd rect
			(at 0 1.0668)
			(size 0.762 1.1684)
			(layers "F.Cu" "F.Mask" "F.Paste")
			(net "TEMP_ALM#_REVERSE_R")
		)
	)
	(footprint ""
		(layer "F.Cu")
		(at 13.1318 -150.622 90)
		(property "Reference" "D2"
			(at 0 0 90)
			(layer "F.SilkS")
			(hide yes)
			(effects
				(font
					(size 1.27 1.27)
				)
			)
		)
		(property "Value" "BAS16H-GP"
			(at 0 -5.5372 90)
			(unlocked yes)
			(layer "F.Fab")
			(hide yes)
			(effects
				(font
					(size 1.016 1.016)
					(thickness 0.1524)
				)
			)
		)
		(property "Device Type" "SOD123AKH48"
			(at 0 -7.0612 90)
			(unlocked yes)
			(layer "F.Fab")
			(hide yes)
			(effects
				(font
					(size 1.016 1.016)
					(thickness 0.1524)
				)
			)
		)
		(duplicate_pad_numbers_are_jumpers no)
		(fp_line
			(start 1.016 -2.667)
			(end -1.016 -2.667)
			(stroke
				(width 0.1524)
				(type default)
			)
			(layer "F.SilkS")
		)
		(fp_line
			(start -1.016 -2.667)
			(end -1.016 2.667)
			(stroke
				(width 0.1524)
				(type default)
			)
			(layer "F.SilkS")
		)
		(fp_line
			(start 1.016 2.667)
			(end 1.016 -2.667)
			(stroke
				(width 0.1524)
				(type default)
			)
			(layer "F.SilkS")
		)
		(fp_line
			(start -1.016 2.667)
			(end 1.016 2.667)
			(stroke
				(width 0.1524)
				(type default)
			)
			(layer "F.SilkS")
		)
		(fp_line
			(start 0.889 2.921)
			(end -0.889 2.921)
			(stroke
				(width 0.508)
				(type default)
			)
			(layer "F.SilkS")
		)
		(fp_rect
			(start -1.143 3.175)
			(end 1.143 -2.794)
			(stroke
				(width 0)
				(type default)
			)
			(fill no)
			(layer "F.CrtYd")
		)
		(fp_poly
			(pts
				(xy -1.143 -2.794) (xy 1.143 -2.794) (xy 1.143 3.175) (xy -1.143 3.175)
			)
			(stroke
				(width 0)
				(type default)
			)
			(fill no)
			(layer "F.Fab")
		)
		(pad "A" smd rect
			(at 0 -1.6891 90)
			(size 0.889 1.397)
			(layers "F.Cu" "F.Mask" "F.Paste")
			(net "FAN_TACH10")
		)
		(pad "K" smd rect
			(at 0 1.6891 90)
			(size 0.889 1.397)
			(layers "F.Cu" "F.Mask" "F.Paste")
			(net "P12V")
		)
	)
	(footprint ""
		(layer "F.Cu")
		(at 29.7942 -167.6908 -90)
		(property "Reference" "R165"
			(at 0 0 270)
			(layer "F.SilkS")
			(hide yes)
			(effects
				(font
					(size 1.27 1.27)
				)
			)
		)
		(property "Value" "0R2J-2-GP"
			(at 0.064008 -3.993896 270)
			(unlocked yes)
			(layer "F.Fab")
			(hide yes)
			(effects
				(font
					(size 1.016 1.016)
					(thickness 0.1524)
				)
			)
		)
		(property "Device Type" "R402H16"
			(at 0.064008 -5.517896 270)
			(unlocked yes)
			(layer "F.Fab")
			(hide yes)
			(effects
				(font
					(size 1.016 1.016)
					(thickness 0.1524)
				)
			)
		)
		(duplicate_pad_numbers_are_jumpers no)
		(fp_line
			(start -0.508 -0.9398)
			(end -0.508 0.9398)
			(stroke
				(width 0.1524)
				(type default)
			)
			(layer "F.SilkS")
		)
		(fp_line
			(start 0.508 -0.9398)
			(end -0.508 -0.9398)
			(stroke
				(width 0.1524)
				(type default)
			)
			(layer "F.SilkS")
		)
		(fp_rect
			(start -0.508 0.9398)
			(end 0.508 -0.9398)
			(stroke
				(width 0)
				(type default)
			)
			(fill no)
			(layer "F.CrtYd")
		)
		(fp_rect
			(start -0.508 0.9398)
			(end 0.508 -0.9398)
			(stroke
				(width 0)
				(type default)
			)
			(fill no)
			(layer "F.Fab")
		)
		(pad "1" smd custom
			(at 0 -0.4445 270)
			(size 0.1397 0.1397)
			(layers "F.Cu" "F.Mask" "F.Paste")
			(net "PWM_BUFFER_IN_FAN1_FAN2")
			(options
				(clearance outline)
				(anchor circle)
			)
			(primitives
				(gr_poly
					(pts
						(arc
							(start -0.1778 -0.2794)
							(mid -0.249642 -0.249642)
							(end -0.2794 -0.1778)
						)
						(arc
							(start -0.2794 0.1778)
							(mid -0.249642 0.249642)
							(end -0.1778 0.2794)
						)
						(arc
							(start 0.1778 0.2794)
							(mid 0.249642 0.249642)
							(end 0.2794 0.1778)
						)
						(arc
							(start 0.2794 -0.1778)
							(mid 0.249642 -0.249642)
							(end 0.1778 -0.2794)
						)
					)
					(width 0)
					(fill yes)
				)
			)
		)
		(pad "2" smd custom
			(at 0 0.4445 270)
			(size 0.1397 0.1397)
			(layers "F.Cu" "F.Mask" "F.Paste")
			(net "PWM_BUFFER_IN_FAN3_FAN4")
			(options
				(clearance outline)
				(anchor circle)
			)
			(primitives
				(gr_poly
					(pts
						(arc
							(start -0.1778 -0.2794)
							(mid -0.249642 -0.249642)
							(end -0.2794 -0.1778)
						)
						(arc
							(start -0.2794 0.1778)
							(mid -0.249642 0.249642)
							(end -0.1778 0.2794)
						)
						(arc
							(start 0.1778 0.2794)
							(mid 0.249642 0.249642)
							(end 0.2794 0.1778)
						)
						(arc
							(start 0.2794 -0.1778)
							(mid 0.249642 -0.249642)
							(end 0.1778 -0.2794)
						)
					)
					(width 0)
					(fill yes)
				)
			)
		)
	)
	(footprint ""
		(layer "F.Cu")
		(at 30.3784 -111.125 90)
		(property "Reference" "PR102"
			(at 0 0 90)
			(layer "F.SilkS")
			(hide yes)
			(effects
				(font
					(size 1.27 1.27)
				)
			)
		)
		(property "Value" "10R2F-L-GP"
			(at 0.064008 -3.993896 90)
			(unlocked yes)
			(layer "F.Fab")
			(hide yes)
			(effects
				(font
					(size 1.016 1.016)
					(thickness 0.1524)
				)
			)
		)
		(property "Device Type" "R402H14"
			(at 0.064008 -5.517896 90)
			(unlocked yes)
			(layer "F.Fab")
			(hide yes)
			(effects
				(font
					(size 1.016 1.016)
					(thickness 0.1524)
				)
			)
		)
		(duplicate_pad_numbers_are_jumpers no)
		(fp_line
			(start 0.508 -0.9398)
			(end -0.508 -0.9398)
			(stroke
				(width 0.1524)
				(type default)
			)
			(layer "F.SilkS")
		)
		(fp_line
			(start -0.508 -0.9398)
			(end -0.508 0.9398)
			(stroke
				(width 0.1524)
				(type default)
			)
			(layer "F.SilkS")
		)
		(fp_rect
			(start -0.508 0.9398)
			(end 0.508 -0.9398)
			(stroke
				(width 0)
				(type default)
			)
			(fill no)
			(layer "F.CrtYd")
		)
		(fp_rect
			(start -0.508 0.9398)
			(end 0.508 -0.9398)
			(stroke
				(width 0)
				(type default)
			)
			(fill no)
			(layer "F.Fab")
		)
		(pad "1" smd custom
			(at 0 -0.4445 90)
			(size 0.1397 0.1397)
			(layers "F.Cu" "F.Mask" "F.Paste")
			(net "P12VU_2490_GATE_DRV")
			(options
				(clearance outline)
				(anchor circle)
			)
			(primitives
				(gr_poly
					(pts
						(arc
							(start -0.1778 -0.2794)
							(mid -0.249642 -0.249642)
							(end -0.2794 -0.1778)
						)
						(arc
							(start -0.2794 0.1778)
							(mid -0.249642 0.249642)
							(end -0.1778 0.2794)
						)
						(arc
							(start 0.1778 0.2794)
							(mid 0.249642 0.249642)
							(end 0.2794 0.1778)
						)
						(arc
							(start 0.2794 -0.1778)
							(mid 0.249642 -0.249642)
							(end 0.1778 -0.2794)
						)
					)
					(width 0)
					(fill yes)
				)
			)
		)
		(pad "2" smd custom
			(at 0 0.4445 90)
			(size 0.1397 0.1397)
			(layers "F.Cu" "F.Mask" "F.Paste")
			(net "P12VU_2490_GATE")
			(options
				(clearance outline)
				(anchor circle)
			)
			(primitives
				(gr_poly
					(pts
						(arc
							(start -0.1778 -0.2794)
							(mid -0.249642 -0.249642)
							(end -0.2794 -0.1778)
						)
						(arc
							(start -0.2794 0.1778)
							(mid -0.249642 0.249642)
							(end -0.1778 0.2794)
						)
						(arc
							(start 0.1778 0.2794)
							(mid 0.249642 0.249642)
							(end 0.2794 0.1778)
						)
						(arc
							(start 0.2794 -0.1778)
							(mid 0.249642 -0.249642)
							(end 0.1778 -0.2794)
						)
					)
					(width 0)
					(fill yes)
				)
			)
		)
	)
	(footprint ""
		(layer "F.Cu")
		(at 13.7922 -66.4464 180)
		(property "Reference" "R151"
			(at 0 0 180)
			(layer "F.SilkS")
			(hide yes)
			(effects
				(font
					(size 1.27 1.27)
				)
			)
		)
		(property "Value" "10R2F-L-GP"
			(at 0.064008 -3.993896 180)
			(unlocked yes)
			(layer "F.Fab")
			(hide yes)
			(effects
				(font
					(size 1.016 1.016)
					(thickness 0.1524)
				)
			)
		)
		(property "Device Type" "R402H14"
			(at 0.064008 -5.517896 180)
			(unlocked yes)
			(layer "F.Fab")
			(hide yes)
			(effects
				(font
					(size 1.016 1.016)
					(thickness 0.1524)
				)
			)
		)
		(duplicate_pad_numbers_are_jumpers no)
		(fp_line
			(start 0.508 -0.9398)
			(end -0.508 -0.9398)
			(stroke
				(width 0.1524)
				(type default)
			)
			(layer "F.SilkS")
		)
		(fp_line
			(start -0.508 -0.9398)
			(end -0.508 0.9398)
			(stroke
				(width 0.1524)
				(type default)
			)
			(layer "F.SilkS")
		)
		(fp_rect
			(start -0.508 0.9398)
			(end 0.508 -0.9398)
			(stroke
				(width 0)
				(type default)
			)
			(fill no)
			(layer "F.CrtYd")
		)
		(fp_rect
			(start -0.508 0.9398)
			(end 0.508 -0.9398)
			(stroke
				(width 0)
				(type default)
			)
			(fill no)
			(layer "F.Fab")
		)
		(pad "1" smd custom
			(at 0 -0.4445 180)
			(size 0.1397 0.1397)
			(layers "F.Cu" "F.Mask" "F.Paste")
			(net "I2C_C_SCL_CONN_R")
			(options
				(clearance outline)
				(anchor circle)
			)
			(primitives
				(gr_poly
					(pts
						(arc
							(start -0.1778 -0.2794)
							(mid -0.249642 -0.249642)
							(end -0.2794 -0.1778)
						)
						(arc
							(start -0.2794 0.1778)
							(mid -0.249642 0.249642)
							(end -0.1778 0.2794)
						)
						(arc
							(start 0.1778 0.2794)
							(mid 0.249642 0.249642)
							(end 0.2794 0.1778)
						)
						(arc
							(start 0.2794 -0.1778)
							(mid 0.249642 -0.249642)
							(end 0.1778 -0.2794)
						)
					)
					(width 0)
					(fill yes)
				)
			)
		)
		(pad "2" smd custom
			(at 0 0.4445 180)
			(size 0.1397 0.1397)
			(layers "F.Cu" "F.Mask" "F.Paste")
			(net "I2C_C_SCL")
			(options
				(clearance outline)
				(anchor circle)
			)
			(primitives
				(gr_poly
					(pts
						(arc
							(start -0.1778 -0.2794)
							(mid -0.249642 -0.249642)
							(end -0.2794 -0.1778)
						)
						(arc
							(start -0.2794 0.1778)
							(mid -0.249642 0.249642)
							(end -0.1778 0.2794)
						)
						(arc
							(start 0.1778 0.2794)
							(mid 0.249642 0.249642)
							(end 0.2794 0.1778)
						)
						(arc
							(start 0.2794 -0.1778)
							(mid 0.249642 -0.249642)
							(end 0.1778 -0.2794)
						)
					)
					(width 0)
					(fill yes)
				)
			)
		)
	)
)
